(kicad_pcb
	(version 20260206)
	(generator "pcbnew")
	(generator_version "10.0")
	(general
		(thickness 1.6)
		(legacy_teardrops no)
	)
	(paper "A4")
	(title_block
		(title "timecard-production-celestica-r4006 — R4006-B0001-02_R01.brd")
		(comment 1 "Time Appliance Project (Time Card) / footprints 574-579 of 1113")
	)
	(layers
		(0 "F.Cu" signal "TOP")
		(4 "In1.Cu" signal "L02_GND1")
		(6 "In2.Cu" signal "L03_SIG1")
		(8 "In3.Cu" signal "L04_GND2")
		(10 "In4.Cu" signal "L05_VCC1")
		(12 "In5.Cu" signal "L06_VCC2")
		(14 "In6.Cu" signal "L07_GND3")
		(16 "In7.Cu" signal "L08_SIG2")
		(18 "In8.Cu" signal "L09_GND4")
		(2 "B.Cu" signal "BOTTOM")
		(9 "F.Adhes" user "F.Adhesive")
		(11 "B.Adhes" user "B.Adhesive")
		(13 "F.Paste" user "Package Geometry/Pastemask Top")
		(15 "B.Paste" user "Package Geometry/Pastemask Bottom")
		(5 "F.SilkS" user "Ref Des/Silkscreen Top")
		(7 "B.SilkS" user "Ref Des/Silkscreen Bottom")
		(1 "F.Mask" user "Board Geometry/Soldermask Top")
		(3 "B.Mask" user "Board Geometry/Soldermask Bottom")
		(17 "Dwgs.User" user "User.Drawings")
		(19 "Cmts.User" user "User.Comments")
		(21 "Eco1.User" user "User.Eco1")
		(23 "Eco2.User" user "User.Eco2")
		(25 "Edge.Cuts" user "Board Geometry/Outline")
		(27 "Margin" user)
		(31 "F.CrtYd" user "Package Geometry/Place Bound Top")
		(29 "B.CrtYd" user "Package Geometry/Place Bound Bottom")
		(35 "F.Fab" user "Ref Des/Assembly Top")
		(33 "B.Fab" user "Ref Des/Assembly Bottom")
	)
	(footprint ""
		(layer "F.Cu")
		(at 145.8214 -89.3318)
		(property "Reference" "R5"
			(at -0.2794 7.96417 0)
			(unlocked yes)
			(layer "F.SilkS")
			(effects
				(font
					(size 0.7874 0.5842)
					(thickness 0.1524)
				)
			)
		)
		(property "Value" "VAL*"
			(at 0.02032 2.13233 0)
			(unlocked yes)
			(layer "F.Fab")
			(hide yes)
			(effects
				(font
					(size 0.7874 0.5842)
					(thickness 0.1524)
				)
			)
		)
		(property "Device Type" "RESISTOR-G155-11002-01,10KOHM,A"
			(at 0.008382 1.210564 0)
			(unlocked yes)
			(layer "F.Fab")
			(hide yes)
			(effects
				(font
					(size 0.7874 0.5842)
					(thickness 0.1524)
				)
			)
		)
		(property "User Part Number" "PARTNUM*"
			(at 0.02032 4.024884 0)
			(unlocked yes)
			(layer "Cmts.User")
			(hide yes)
			(effects
				(font
					(size 0.7874 0.5842)
					(thickness 0.1524)
				)
			)
		)
		(property "Tolerance" "TOL*"
			(at 0.044704 3.05435 0)
			(unlocked yes)
			(layer "Cmts.User")
			(hide yes)
			(effects
				(font
					(size 0.7874 0.5842)
					(thickness 0.1524)
				)
			)
		)
		(duplicate_pad_numbers_are_jumpers no)
		(fp_line
			(start -1.143 -0.5588)
			(end -1.143 0.5588)
			(stroke
				(width 0.1)
				(type default)
			)
			(layer "F.SilkS")
		)
		(fp_line
			(start -1.143 0.5588)
			(end 1.143 0.5588)
			(stroke
				(width 0.1)
				(type default)
			)
			(layer "F.SilkS")
		)
		(fp_line
			(start 1.143 -0.5588)
			(end -1.143 -0.5588)
			(stroke
				(width 0.1)
				(type default)
			)
			(layer "F.SilkS")
		)
		(fp_line
			(start 1.143 0.5588)
			(end 1.143 -0.5588)
			(stroke
				(width 0.1)
				(type default)
			)
			(layer "F.SilkS")
		)
		(fp_rect
			(start -1.143 -0.5588)
			(end 1.143 0.5588)
			(stroke
				(width 0)
				(type default)
			)
			(fill no)
			(layer "F.CrtYd")
		)
		(fp_line
			(start -0.508 -0.3048)
			(end -0.508 0.3048)
			(stroke
				(width 0.1)
				(type default)
			)
			(layer "F.Fab")
		)
		(fp_line
			(start -0.508 0.3048)
			(end 0.508 0.3048)
			(stroke
				(width 0.1)
				(type default)
			)
			(layer "F.Fab")
		)
		(fp_line
			(start 0.508 -0.3048)
			(end -0.508 -0.3048)
			(stroke
				(width 0.1)
				(type default)
			)
			(layer "F.Fab")
		)
		(fp_line
			(start 0.508 0.3048)
			(end 0.508 -0.3048)
			(stroke
				(width 0.1)
				(type default)
			)
			(layer "F.Fab")
		)
		(pad "1" smd rect
			(at -0.5334 0)
			(size 0.7112 0.6096)
			(layers "F.Cu" "F.Mask" "F.Paste")
			(net "XP12R0V_A_EN")
		)
		(pad "2" smd rect
			(at 0.5334 0)
			(size 0.7112 0.6096)
			(layers "F.Cu" "F.Mask" "F.Paste")
			(net "SG")
		)
		(zone
			(layer "F.Cu")
			(hatch none 0.5)
			(connect_pads
				(clearance 0)
			)
			(min_thickness 0.25)
			(keepout
				(tracks allowed)
				(vias not_allowed)
				(pads allowed)
				(copperpour not_allowed)
				(footprints allowed)
			)
			(placement
				(enabled no)
				(sheetname "")
			)
			(fill
				(thermal_gap 0.5)
				(thermal_bridge_width 0.5)
				(island_removal_mode 0)
			)
			(polygon
				(pts
					(xy 145.7452 -89.6366) (xy 145.7452 -89.027) (xy 145.8976 -89.027) (xy 145.8976 -89.6366)
				)
			)
		)
	)
	(footprint ""
		(layer "F.Cu")
		(at 125.984 -66.421 90)
		(property "Reference" "R166"
			(at 5.42163 0.127 0)
			(unlocked yes)
			(layer "F.SilkS")
			(effects
				(font
					(size 0.7874 0.5842)
					(thickness 0.1524)
				)
			)
		)
		(property "Value" "VAL*"
			(at 0.0508 2.245106 90)
			(unlocked yes)
			(layer "F.Fab")
			(hide yes)
			(effects
				(font
					(size 0.7874 0.5842)
					(thickness 0.1524)
				)
			)
		)
		(property "Tolerance" "TOL*"
			(at 0.0508 3.261106 90)
			(unlocked yes)
			(layer "Cmts.User")
			(hide yes)
			(effects
				(font
					(size 0.7874 0.5842)
					(thickness 0.1524)
				)
			)
		)
		(property "Device Type" "RESISTOR-G152-00055-01,1.13KOHA"
			(at 0.0762 1.254506 90)
			(unlocked yes)
			(layer "F.Fab")
			(hide yes)
			(effects
				(font
					(size 0.7874 0.5842)
					(thickness 0.1524)
				)
			)
		)
		(property "User Part Number" "PARTNUM*"
			(at 0.0762 4.302506 90)
			(unlocked yes)
			(layer "Cmts.User")
			(hide yes)
			(effects
				(font
					(size 0.7874 0.5842)
					(thickness 0.1524)
				)
			)
		)
		(duplicate_pad_numbers_are_jumpers no)
		(fp_line
			(start 1.143 -0.5588)
			(end -1.143 -0.5588)
			(stroke
				(width 0.1)
				(type default)
			)
			(layer "F.SilkS")
		)
		(fp_line
			(start -1.143 -0.5588)
			(end -1.143 0.5588)
			(stroke
				(width 0.1)
				(type default)
			)
			(layer "F.SilkS")
		)
		(fp_line
			(start 1.143 0.5588)
			(end 1.143 -0.5588)
			(stroke
				(width 0.1)
				(type default)
			)
			(layer "F.SilkS")
		)
		(fp_line
			(start -1.143 0.5588)
			(end 1.143 0.5588)
			(stroke
				(width 0.1)
				(type default)
			)
			(layer "F.SilkS")
		)
		(fp_rect
			(start 1.143 -0.5588)
			(end -1.143 0.5588)
			(stroke
				(width 0)
				(type default)
			)
			(fill no)
			(layer "F.CrtYd")
		)
		(fp_line
			(start 0.508 -0.3048)
			(end -0.508 -0.3048)
			(stroke
				(width 0.1)
				(type default)
			)
			(layer "F.Fab")
		)
		(fp_line
			(start -0.508 -0.3048)
			(end -0.508 0.3048)
			(stroke
				(width 0.1)
				(type default)
			)
			(layer "F.Fab")
		)
		(fp_line
			(start 0.508 0.3048)
			(end 0.508 -0.3048)
			(stroke
				(width 0.1)
				(type default)
			)
			(layer "F.Fab")
		)
		(fp_line
			(start -0.508 0.3048)
			(end 0.508 0.3048)
			(stroke
				(width 0.1)
				(type default)
			)
			(layer "F.Fab")
		)
		(pad "1" smd rect
			(at -0.5334 0 90)
			(size 0.7112 0.6096)
			(layers "F.Cu" "F.Mask" "F.Paste")
			(net "XP1R8V_VIN")
		)
		(pad "2" smd rect
			(at 0.5334 0 90)
			(size 0.7112 0.6096)
			(layers "F.Cu" "F.Mask" "F.Paste")
			(net "XP1R8V_EN_R")
		)
		(zone
			(layer "F.Cu")
			(hatch none 0.5)
			(connect_pads
				(clearance 0)
			)
			(min_thickness 0.25)
			(keepout
				(tracks allowed)
				(vias not_allowed)
				(pads allowed)
				(copperpour not_allowed)
				(footprints allowed)
			)
			(placement
				(enabled no)
				(sheetname "")
			)
			(fill
				(thermal_gap 0.5)
				(thermal_bridge_width 0.5)
				(island_removal_mode 0)
			)
			(polygon
				(pts
					(xy 125.6792 -66.4972) (xy 125.6792 -66.3448) (xy 126.2888 -66.3448) (xy 126.2888 -66.4972)
				)
			)
		)
	)
	(footprint ""
		(layer "F.Cu")
		(at 117.475 -98.044 180)
		(property "Reference" "L16"
			(at 1.0795 -1.43637 0)
			(unlocked yes)
			(layer "F.SilkS")
			(effects
				(font
					(size 0.7874 0.5842)
					(thickness 0.1524)
				)
				(justify left)
			)
		)
		(property "Value" "VAL*"
			(at -0.9398 3.70967 180)
			(unlocked yes)
			(layer "F.Fab")
			(hide yes)
			(effects
				(font
					(size 0.7874 0.5842)
					(thickness 0.1524)
				)
				(justify left)
			)
		)
		(property "Tolerance" "TOL*"
			(at -0.9906 5.00507 180)
			(unlocked yes)
			(layer "Cmts.User")
			(hide yes)
			(effects
				(font
					(size 0.7874 0.5842)
					(thickness 0.1524)
				)
				(justify left)
			)
		)
		(property "User Part Number" "PARTNUM*"
			(at -2.54 2.46507 180)
			(unlocked yes)
			(layer "Cmts.User")
			(hide yes)
			(effects
				(font
					(size 0.7874 0.5842)
					(thickness 0.1524)
				)
				(justify left)
			)
		)
		(property "Device Type" "FERRITEBEAD-G191-10100-01,120OA"
			(at -0.9906 1.22047 180)
			(unlocked yes)
			(layer "F.Fab")
			(hide yes)
			(effects
				(font
					(size 0.7874 0.5842)
					(thickness 0.1524)
				)
				(justify left)
			)
		)
		(duplicate_pad_numbers_are_jumpers no)
		(fp_line
			(start 1.3208 0.7112)
			(end -1.3208 0.7112)
			(stroke
				(width 0.1)
				(type default)
			)
			(layer "F.SilkS")
		)
		(fp_line
			(start 1.3208 -0.7112)
			(end 1.3208 0.7112)
			(stroke
				(width 0.1)
				(type default)
			)
			(layer "F.SilkS")
		)
		(fp_line
			(start -1.3208 0.7112)
			(end -1.3208 -0.7112)
			(stroke
				(width 0.1)
				(type default)
			)
			(layer "F.SilkS")
		)
		(fp_line
			(start -1.3208 -0.7112)
			(end 1.3208 -0.7112)
			(stroke
				(width 0.1)
				(type default)
			)
			(layer "F.SilkS")
		)
		(fp_rect
			(start -1.3208 0.7112)
			(end 1.3208 -0.7112)
			(stroke
				(width 0)
				(type default)
			)
			(fill no)
			(layer "F.CrtYd")
		)
		(fp_line
			(start 0.8128 0.4572)
			(end -0.8128 0.4572)
			(stroke
				(width 0.1)
				(type default)
			)
			(layer "F.Fab")
		)
		(fp_line
			(start 0.8128 -0.4572)
			(end 0.8128 0.4572)
			(stroke
				(width 0.1)
				(type default)
			)
			(layer "F.Fab")
		)
		(fp_line
			(start -0.8128 0.4572)
			(end -0.8128 -0.4572)
			(stroke
				(width 0.1)
				(type default)
			)
			(layer "F.Fab")
		)
		(fp_line
			(start -0.8128 -0.4572)
			(end 0.8128 -0.4572)
			(stroke
				(width 0.1)
				(type default)
			)
			(layer "F.Fab")
		)
		(pad "1" smd rect
			(at -0.6858 0 180)
			(size 0.762 0.8636)
			(layers "F.Cu" "F.Mask" "F.Paste")
			(net "XP3R3V_GPS")
		)
		(pad "2" smd rect
			(at 0.6858 0 180)
			(size 0.762 0.8636)
			(layers "F.Cu" "F.Mask" "F.Paste")
			(net "XP3R3V_FPGA")
		)
		(zone
			(layer "F.Cu")
			(hatch none 0.5)
			(connect_pads
				(clearance 0)
			)
			(min_thickness 0.25)
			(keepout
				(tracks allowed)
				(vias not_allowed)
				(pads allowed)
				(copperpour not_allowed)
				(footprints allowed)
			)
			(placement
				(enabled no)
				(sheetname "")
			)
			(fill
				(thermal_gap 0.5)
				(thermal_bridge_width 0.5)
				(island_removal_mode 0)
			)
			(polygon
				(pts
					(xy 117.6274 -98.5012) (xy 117.3226 -98.5012) (xy 117.3226 -97.5868) (xy 117.6274 -97.5868)
				)
			)
		)
		(zone
			(layer "F.Cu")
			(hatch none 0.5)
			(connect_pads
				(clearance 0)
			)
			(min_thickness 0.25)
			(keepout
				(tracks not_allowed)
				(vias allowed)
				(pads allowed)
				(copperpour not_allowed)
				(footprints allowed)
			)
			(placement
				(enabled no)
				(sheetname "")
			)
			(fill
				(thermal_gap 0.5)
				(thermal_bridge_width 0.5)
				(island_removal_mode 0)
			)
			(polygon
				(pts
					(xy 117.6274 -98.5012) (xy 117.3226 -98.5012) (xy 117.3226 -97.5868) (xy 117.6274 -97.5868)
				)
			)
		)
	)
	(footprint ""
		(layer "F.Cu")
		(at 111.633 -61.976 -90)
		(property "Reference" "R213"
			(at -3.302 -0.42037 90)
			(unlocked yes)
			(layer "F.SilkS")
			(effects
				(font
					(size 0.7874 0.5842)
					(thickness 0.1524)
				)
			)
		)
		(property "Value" "VAL*"
			(at 0.02032 2.13233 270)
			(unlocked yes)
			(layer "F.Fab")
			(hide yes)
			(effects
				(font
					(size 0.7874 0.5842)
					(thickness 0.1524)
				)
			)
		)
		(property "Device Type" "RESISTOR-G155-11002-01,10KOHM,A"
			(at 0.008382 1.210564 270)
			(unlocked yes)
			(layer "F.Fab")
			(hide yes)
			(effects
				(font
					(size 0.7874 0.5842)
					(thickness 0.1524)
				)
			)
		)
		(property "User Part Number" "PARTNUM*"
			(at 0.02032 4.024884 270)
			(unlocked yes)
			(layer "Cmts.User")
			(hide yes)
			(effects
				(font
					(size 0.7874 0.5842)
					(thickness 0.1524)
				)
			)
		)
		(property "Tolerance" "TOL*"
			(at 0.044704 3.05435 270)
			(unlocked yes)
			(layer "Cmts.User")
			(hide yes)
			(effects
				(font
					(size 0.7874 0.5842)
					(thickness 0.1524)
				)
			)
		)
		(duplicate_pad_numbers_are_jumpers no)
		(fp_line
			(start -1.143 0.5588)
			(end 1.143 0.5588)
			(stroke
				(width 0.1)
				(type default)
			)
			(layer "F.SilkS")
		)
		(fp_line
			(start 1.143 0.5588)
			(end 1.143 -0.5588)
			(stroke
				(width 0.1)
				(type default)
			)
			(layer "F.SilkS")
		)
		(fp_line
			(start -1.143 -0.5588)
			(end -1.143 0.5588)
			(stroke
				(width 0.1)
				(type default)
			)
			(layer "F.SilkS")
		)
		(fp_line
			(start 1.143 -0.5588)
			(end -1.143 -0.5588)
			(stroke
				(width 0.1)
				(type default)
			)
			(layer "F.SilkS")
		)
		(fp_rect
			(start 1.143 0.5588)
			(end -1.143 -0.5588)
			(stroke
				(width 0)
				(type default)
			)
			(fill no)
			(layer "F.CrtYd")
		)
		(fp_line
			(start -0.508 0.3048)
			(end 0.508 0.3048)
			(stroke
				(width 0.1)
				(type default)
			)
			(layer "F.Fab")
		)
		(fp_line
			(start 0.508 0.3048)
			(end 0.508 -0.3048)
			(stroke
				(width 0.1)
				(type default)
			)
			(layer "F.Fab")
		)
		(fp_line
			(start -0.508 -0.3048)
			(end -0.508 0.3048)
			(stroke
				(width 0.1)
				(type default)
			)
			(layer "F.Fab")
		)
		(fp_line
			(start 0.508 -0.3048)
			(end -0.508 -0.3048)
			(stroke
				(width 0.1)
				(type default)
			)
			(layer "F.Fab")
		)
		(pad "1" smd rect
			(at -0.5334 0 270)
			(size 0.7112 0.6096)
			(layers "F.Cu" "F.Mask" "F.Paste")
			(net "XP3R3V_FPGA")
		)
		(pad "2" smd rect
			(at 0.5334 0 270)
			(size 0.7112 0.6096)
			(layers "F.Cu" "F.Mask" "F.Paste")
			(net "FPGA_BRD_REV2")
		)
		(zone
			(layer "F.Cu")
			(hatch none 0.5)
			(connect_pads
				(clearance 0)
			)
			(min_thickness 0.25)
			(keepout
				(tracks allowed)
				(vias not_allowed)
				(pads allowed)
				(copperpour not_allowed)
				(footprints allowed)
			)
			(placement
				(enabled no)
				(sheetname "")
			)
			(fill
				(thermal_gap 0.5)
				(thermal_bridge_width 0.5)
				(island_removal_mode 0)
			)
			(polygon
				(pts
					(xy 111.3282 -61.8998) (xy 111.9378 -61.8998) (xy 111.9378 -62.0522) (xy 111.3282 -62.0522)
				)
			)
		)
	)
	(footprint ""
		(layer "F.Cu")
		(at 24.13 -74.041 90)
		(property "Reference" "TP10"
			(at 0 0 90)
			(layer "F.SilkS")
			(hide yes)
			(effects
				(font
					(size 1.27 1.27)
				)
			)
		)
		(property "Value" ""
			(at 0 0 90)
			(layer "F.Fab")
			(effects
				(font
					(size 1.27 1.27)
				)
			)
		)
		(property "Device Type" "TP_PIONT-TP010CT020B030_PTH-TPA"
			(at -1.341882 0.996696 90)
			(unlocked yes)
			(layer "F.Fab")
			(hide yes)
			(effects
				(font
					(size 0.7874 0.5842)
					(thickness 0.1524)
				)
				(justify left)
			)
		)
		(duplicate_pad_numbers_are_jumpers no)
		(fp_poly
			(pts
				(arc
					(start 0 0.889)
					(mid 0 -0.889)
					(end 0 0.889)
				)
			)
			(stroke
				(width 0)
				(type default)
			)
			(fill no)
			(layer "B.CrtYd")
		)
		(fp_poly
			(pts
				(arc
					(start 0 0.889)
					(mid 0 -0.889)
					(end 0 0.889)
				)
			)
			(stroke
				(width 0)
				(type default)
			)
			(fill no)
			(layer "F.CrtYd")
		)
		(pad "1" thru_hole circle
			(at 0 0 90)
			(size 0.508 0.508)
			(drill 0.254)
			(layers "*.Cu" "*.Mask")
			(remove_unused_layers no)
			(net "UNNAMED_524_FT4232HLREELQFP64_5")
			(clearance 0.1016)
			(padstack
				(mode front_inner_back)
				(layer "Inner"
					(shape circle)
					(size 0.508 0.508)
					(clearance 0.1016)
				)
				(layer "B.Cu"
					(shape circle)
					(size 0.762 0.762)
					(clearance -0.0254)
				)
			)
		)
	)
	(footprint ""
		(layer "F.Cu")
		(at 105.8418 -74.5744 180)
		(property "Reference" "C238"
			(at -0.3302 -5.00507 0)
			(unlocked yes)
			(layer "F.SilkS")
			(effects
				(font
					(size 0.7874 0.5842)
					(thickness 0.1524)
				)
			)
		)
		(property "Value" "VAL*"
			(at 0.0762 3.134106 180)
			(unlocked yes)
			(layer "F.Fab")
			(hide yes)
			(effects
				(font
					(size 0.7874 0.5842)
					(thickness 0.1524)
				)
			)
		)
		(property "Device Type" "CAPACITOR-G107-0F226-CM,22UF,2A"
			(at 0.0508 2.194306 180)
			(unlocked yes)
			(layer "F.Fab")
			(hide yes)
			(effects
				(font
					(size 0.7874 0.5842)
					(thickness 0.1524)
				)
			)
		)
		(property "User Part Number" "PARTNUM*"
			(at 0.1016 5.013706 180)
			(unlocked yes)
			(layer "Cmts.User")
			(hide yes)
			(effects
				(font
					(size 0.7874 0.5842)
					(thickness 0.1524)
				)
			)
		)
		(property "Tolerance" "TOL*"
			(at 0.0762 4.048506 180)
			(unlocked yes)
			(layer "Cmts.User")
			(hide yes)
			(effects
				(font
					(size 0.7874 0.5842)
					(thickness 0.1524)
				)
			)
		)
		(duplicate_pad_numbers_are_jumpers no)
		(fp_line
			(start 1.5748 0.9398)
			(end 1.5748 -0.9398)
			(stroke
				(width 0.1)
				(type default)
			)
			(layer "F.SilkS")
		)
		(fp_line
			(start 1.5748 -0.9398)
			(end -1.5748 -0.9398)
			(stroke
				(width 0.1)
				(type default)
			)
			(layer "F.SilkS")
		)
		(fp_line
			(start -1.5748 0.9398)
			(end 1.5748 0.9398)
			(stroke
				(width 0.1)
				(type default)
			)
			(layer "F.SilkS")
		)
		(fp_line
			(start -1.5748 -0.9398)
			(end -1.5748 0.9398)
			(stroke
				(width 0.1)
				(type default)
			)
			(layer "F.SilkS")
		)
		(fp_rect
			(start -1.5748 0.9398)
			(end 1.5748 -0.9398)
			(stroke
				(width 0)
				(type default)
			)
			(fill no)
			(layer "F.CrtYd")
		)
		(fp_line
			(start 1.016 0.635)
			(end 1.016 -0.635)
			(stroke
				(width 0.1)
				(type default)
			)
			(layer "F.Fab")
		)
		(fp_line
			(start 1.016 -0.635)
			(end -1.016 -0.635)
			(stroke
				(width 0.1)
				(type default)
			)
			(layer "F.Fab")
		)
		(fp_line
			(start -1.016 0.635)
			(end 1.016 0.635)
			(stroke
				(width 0.1)
				(type default)
			)
			(layer "F.Fab")
		)
		(fp_line
			(start -1.016 -0.635)
			(end -1.016 0.635)
			(stroke
				(width 0.1)
				(type default)
			)
			(layer "F.Fab")
		)
		(pad "1" smd rect
			(at -0.8382 0 180)
			(size 0.9652 1.3716)
			(layers "F.Cu" "F.Mask" "F.Paste")
			(net "XP3R3V_FPGA")
		)
		(pad "2" smd rect
			(at 0.8382 0 180)
			(size 0.9652 1.3716)
			(layers "F.Cu" "F.Mask" "F.Paste")
			(net "SG")
		)
		(zone
			(layer "F.Cu")
			(hatch none 0.5)
			(connect_pads
				(clearance 0)
			)
			(min_thickness 0.25)
			(keepout
				(tracks allowed)
				(vias not_allowed)
				(pads allowed)
				(copperpour not_allowed)
				(footprints allowed)
			)
			(placement
				(enabled no)
				(sheetname "")
			)
			(fill
				(thermal_gap 0.5)
				(thermal_bridge_width 0.5)
				(island_removal_mode 0)
			)
			(polygon
				(pts
					(xy 106.0704 -75.2094) (xy 105.6132 -75.2094) (xy 105.6132 -73.9394) (xy 106.0704 -73.9394)
				)
			)
		)
	)
)
